# T6G (Grand Teton) — schematic netlist excerpt (pin names and nets, part order shuffled) for the footprints in the layout excerpt that follows; sources: Cadence DE-HDL packaged netlist, KiCad conversion of 04192023_DAF0TMB3IC0_F0TG_MB_C_brd_V02_OCP.brd

PC612_3  Q_CAP  22UF 16V 20% X6S  pkg C0805  page 199 : A = SW_P12V_AUX_PVDDCR_SOC_P0_FLT ; B = GND
PC6579_2  Q_CAP  22UF 16V 20% X6S  pkg C0805  page 363 : A = SW_P12V_AUX_P0V9_RETIMER_CPU0_FLT ; B = GND
C6040  Q_CAP  0.01UF 50V 10% X7R  pkg C0402  page 177 : A = P3V3_AUX ; B = GND

(kicad_pcb
	(version 20260206)
	(generator "pcbnew")
	(generator_version "10.0")
	(general
		(thickness 1.6)
		(legacy_teardrops no)
	)
	(paper "A4")
	(title_block
		(title "04192023_DAF0TMB3IC0_F0TG_MB_C_brd_V02_OCP.brd")
		(comment 1 "Grand Teton / footprints 5309-5311 of 8354")
	)
	(layers
		(0 "F.Cu" signal "TOP")
		(4 "In1.Cu" signal "GND")
		(6 "In2.Cu" signal "IN1")
		(8 "In3.Cu" signal "GND1")
		(10 "In4.Cu" signal "IN2")
		(12 "In5.Cu" signal "GND2")
		(14 "In6.Cu" signal "IN3")
		(16 "In7.Cu" signal "GND3")
		(18 "In8.Cu" signal "VCC")
		(20 "In9.Cu" signal "VCC1")
		(22 "In10.Cu" signal "GND4")
		(24 "In11.Cu" signal "IN4")
		(26 "In12.Cu" signal "GND5")
		(28 "In13.Cu" signal "IN5")
		(30 "In14.Cu" signal "GND6")
		(32 "In15.Cu" signal "IN6")
		(34 "In16.Cu" signal "GND7")
		(2 "B.Cu" signal "BOTTOM")
		(9 "F.Adhes" user "F.Adhesive")
		(11 "B.Adhes" user "B.Adhesive")
		(13 "F.Paste" user "Package Geometry/Pastemask Top")
		(15 "B.Paste" user "Package Geometry/Pastemask Bottom")
		(5 "F.SilkS" user "Ref Des/Silkscreen Top")
		(7 "B.SilkS" user "Ref Des/Silkscreen Bottom")
		(1 "F.Mask" user "Board Geometry/Soldermask Top")
		(3 "B.Mask" user "Board Geometry/Soldermask Bottom")
		(17 "Dwgs.User" user "User.Drawings")
		(19 "Cmts.User" user "User.Comments")
		(21 "Eco1.User" user "User.Eco1")
		(23 "Eco2.User" user "User.Eco2")
		(25 "Edge.Cuts" user "Board Geometry/Outline")
		(27 "Margin" user)
		(31 "F.CrtYd" user "Package Geometry/Place Bound Top")
		(29 "B.CrtYd" user "Package Geometry/Place Bound Bottom")
		(35 "F.Fab" user "Ref Des/Assembly Top")
		(33 "B.Fab" user "Ref Des/Assembly Bottom")
	)
	(footprint ""
		(layer "B.Cu")
		(at 131.474972 -41.007792 90)
		(property "Reference" "C6040"
			(at 0 0 90)
			(layer "B.SilkS")
			(hide yes)
			(effects
				(font
					(size 1.27 1.27)
				)
				(justify mirror)
			)
		)
		(property "Value" ""
			(at 0 0 90)
			(layer "B.Fab")
			(effects
				(font
					(size 1.27 1.27)
				)
				(justify mirror)
			)
		)
		(duplicate_pad_numbers_are_jumpers no)
		(fp_line
			(start 0.7874 -0.4064)
			(end -0.7874 -0.4064)
			(stroke
				(width 0.1524)
				(type default)
			)
			(layer "B.SilkS")
		)
		(fp_line
			(start -0.7874 -0.4064)
			(end -0.7874 0.4064)
			(stroke
				(width 0.1524)
				(type default)
			)
			(layer "B.SilkS")
		)
		(fp_line
			(start 0.7874 0.4064)
			(end 0.7874 -0.4064)
			(stroke
				(width 0.1524)
				(type default)
			)
			(layer "B.SilkS")
		)
		(fp_line
			(start -0.7874 0.4064)
			(end 0.7874 0.4064)
			(stroke
				(width 0.1524)
				(type default)
			)
			(layer "B.SilkS")
		)
		(fp_line
			(start 0.67945 -0.305054)
			(end 0.12065 -0.305054)
			(stroke
				(width 0.1)
				(type default)
			)
			(layer "B.Fab")
		)
		(fp_line
			(start 0.12065 -0.305054)
			(end 0.12065 -0.2794)
			(stroke
				(width 0.1)
				(type default)
			)
			(layer "B.Fab")
		)
		(fp_line
			(start -0.12065 -0.3048)
			(end -0.67945 -0.3048)
			(stroke
				(width 0.1)
				(type default)
			)
			(layer "B.Fab")
		)
		(fp_line
			(start -0.67945 -0.3048)
			(end -0.67945 0.3048)
			(stroke
				(width 0.1)
				(type default)
			)
			(layer "B.Fab")
		)
		(fp_line
			(start 0.12065 -0.2794)
			(end -0.12065 -0.2794)
			(stroke
				(width 0.1)
				(type default)
			)
			(layer "B.Fab")
		)
		(fp_line
			(start -0.12065 -0.2794)
			(end -0.12065 -0.3048)
			(stroke
				(width 0.1)
				(type default)
			)
			(layer "B.Fab")
		)
		(fp_line
			(start 0.12065 0.2794)
			(end 0.12065 0.3048)
			(stroke
				(width 0.1)
				(type default)
			)
			(layer "B.Fab")
		)
		(fp_line
			(start -0.120396 0.2794)
			(end 0.12065 0.2794)
			(stroke
				(width 0.1)
				(type default)
			)
			(layer "B.Fab")
		)
		(fp_line
			(start 0.67945 0.3048)
			(end 0.67945 -0.305054)
			(stroke
				(width 0.1)
				(type default)
			)
			(layer "B.Fab")
		)
		(fp_line
			(start 0.12065 0.3048)
			(end 0.67945 0.3048)
			(stroke
				(width 0.1)
				(type default)
			)
			(layer "B.Fab")
		)
		(fp_line
			(start -0.120396 0.3048)
			(end -0.120396 0.2794)
			(stroke
				(width 0.1)
				(type default)
			)
			(layer "B.Fab")
		)
		(fp_line
			(start -0.67945 0.3048)
			(end -0.120396 0.3048)
			(stroke
				(width 0.1)
				(type default)
			)
			(layer "B.Fab")
		)
		(pad "1" smd circle
			(at 0.40005 0 270)
			(size 0 0)
			(layers "B.Cu" "B.Mask" "B.Paste")
			(net "P3V3_AUX")
		)
		(pad "2" smd circle
			(at -0.40005 0 270)
			(size 0 0)
			(layers "B.Cu" "B.Mask" "B.Paste")
			(net "GND")
		)
	)
	(footprint ""
		(layer "B.Cu")
		(at 409.623768 -162.508438 -90)
		(property "Reference" "PC612_3"
			(at 0 0 90)
			(layer "B.SilkS")
			(hide yes)
			(effects
				(font
					(size 1.27 1.27)
				)
				(justify mirror)
			)
		)
		(property "Value" ""
			(at 0 0 90)
			(layer "B.Fab")
			(effects
				(font
					(size 1.27 1.27)
				)
				(justify mirror)
			)
		)
		(duplicate_pad_numbers_are_jumpers no)
		(fp_line
			(start -1.524 0.762)
			(end 1.524 0.762)
			(stroke
				(width 0.1524)
				(type default)
			)
			(layer "B.SilkS")
		)
		(fp_line
			(start 1.524 0.762)
			(end 1.524 -0.762)
			(stroke
				(width 0.1524)
				(type default)
			)
			(layer "B.SilkS")
		)
		(fp_line
			(start -1.524 -0.762)
			(end -1.524 0.762)
			(stroke
				(width 0.1524)
				(type default)
			)
			(layer "B.SilkS")
		)
		(fp_line
			(start 1.524 -0.762)
			(end -1.524 -0.762)
			(stroke
				(width 0.1524)
				(type default)
			)
			(layer "B.SilkS")
		)
		(fp_line
			(start -1.1049 0.724916)
			(end -1.1049 -0.724916)
			(stroke
				(width 0.1)
				(type default)
			)
			(layer "B.Fab")
		)
		(fp_line
			(start 1.1049 0.724916)
			(end -1.1049 0.724916)
			(stroke
				(width 0.1)
				(type default)
			)
			(layer "B.Fab")
		)
		(fp_line
			(start -1.1049 -0.724916)
			(end 1.1049 -0.724916)
			(stroke
				(width 0.1)
				(type default)
			)
			(layer "B.Fab")
		)
		(fp_line
			(start 1.1049 -0.724916)
			(end 1.1049 0.724916)
			(stroke
				(width 0.1)
				(type default)
			)
			(layer "B.Fab")
		)
		(pad "1" smd rect
			(at 0.889 0 270)
			(size 1.016 1.27)
			(layers "B.Cu" "B.Mask" "B.Paste")
			(net "SW_P12V_AUX_PVDDCR_SOC_P0_FLT")
		)
		(pad "2" smd rect
			(at -0.889 0 270)
			(size 1.016 1.27)
			(layers "B.Cu" "B.Mask" "B.Paste")
			(net "GND")
		)
	)
	(footprint ""
		(layer "B.Cu")
		(at 455.213466 -397.05407 90)
		(property "Reference" "PC6579_2"
			(at 0 0 90)
			(layer "B.SilkS")
			(hide yes)
			(effects
				(font
					(size 1.27 1.27)
				)
				(justify mirror)
			)
		)
		(property "Value" ""
			(at 0 0 90)
			(layer "B.Fab")
			(effects
				(font
					(size 1.27 1.27)
				)
				(justify mirror)
			)
		)
		(duplicate_pad_numbers_are_jumpers no)
		(fp_line
			(start 1.524 -0.762)
			(end -1.524 -0.762)
			(stroke
				(width 0.1524)
				(type default)
			)
			(layer "B.SilkS")
		)
		(fp_line
			(start -1.524 -0.762)
			(end -1.524 0.762)
			(stroke
				(width 0.1524)
				(type default)
			)
			(layer "B.SilkS")
		)
		(fp_line
			(start 1.524 0.762)
			(end 1.524 -0.762)
			(stroke
				(width 0.1524)
				(type default)
			)
			(layer "B.SilkS")
		)
		(fp_line
			(start -1.524 0.762)
			(end 1.524 0.762)
			(stroke
				(width 0.1524)
				(type default)
			)
			(layer "B.SilkS")
		)
		(fp_line
			(start 1.1049 -0.724916)
			(end 1.1049 0.724916)
			(stroke
				(width 0.1)
				(type default)
			)
			(layer "B.Fab")
		)
		(fp_line
			(start -1.1049 -0.724916)
			(end 1.1049 -0.724916)
			(stroke
				(width 0.1)
				(type default)
			)
			(layer "B.Fab")
		)
		(fp_line
			(start 1.1049 0.724916)
			(end -1.1049 0.724916)
			(stroke
				(width 0.1)
				(type default)
			)
			(layer "B.Fab")
		)
		(fp_line
			(start -1.1049 0.724916)
			(end -1.1049 -0.724916)
			(stroke
				(width 0.1)
				(type default)
			)
			(layer "B.Fab")
		)
		(pad "1" smd rect
			(at 0.889 0 90)
			(size 1.016 1.27)
			(layers "B.Cu" "B.Mask" "B.Paste")
			(net "SW_P12V_AUX_P0V9_RETIMER_CPU0_FLT")
		)
		(pad "2" smd rect
			(at -0.889 0 90)
			(size 1.016 1.27)
			(layers "B.Cu" "B.Mask" "B.Paste")
			(net "GND")
		)
	)
)
